(kicad_pcb
	(version 20260206)
	(generator "pcbnew")
	(generator_version "10.0")
	(general
		(thickness 1.6)
		(legacy_teardrops no)
	)
	(paper "A4")
	(title_block
		(title "timecard-production-celestica-r4006 — R4006-B0001-02_R01.brd")
		(comment 1 "Time Appliance Project (Time Card) / footprints 91-95 of 1113")
	)
	(layers
		(0 "F.Cu" signal "TOP")
		(4 "In1.Cu" signal "L02_GND1")
		(6 "In2.Cu" signal "L03_SIG1")
		(8 "In3.Cu" signal "L04_GND2")
		(10 "In4.Cu" signal "L05_VCC1")
		(12 "In5.Cu" signal "L06_VCC2")
		(14 "In6.Cu" signal "L07_GND3")
		(16 "In7.Cu" signal "L08_SIG2")
		(18 "In8.Cu" signal "L09_GND4")
		(2 "B.Cu" signal "BOTTOM")
		(9 "F.Adhes" user "F.Adhesive")
		(11 "B.Adhes" user "B.Adhesive")
		(13 "F.Paste" user "Package Geometry/Pastemask Top")
		(15 "B.Paste" user "Package Geometry/Pastemask Bottom")
		(5 "F.SilkS" user "Ref Des/Silkscreen Top")
		(7 "B.SilkS" user "Ref Des/Silkscreen Bottom")
		(1 "F.Mask" user "Board Geometry/Soldermask Top")
		(3 "B.Mask" user "Board Geometry/Soldermask Bottom")
		(17 "Dwgs.User" user "User.Drawings")
		(19 "Cmts.User" user "User.Comments")
		(21 "Eco1.User" user "User.Eco1")
		(23 "Eco2.User" user "User.Eco2")
		(25 "Edge.Cuts" user "Board Geometry/Outline")
		(27 "Margin" user)
		(31 "F.CrtYd" user "Package Geometry/Place Bound Top")
		(29 "B.CrtYd" user "Package Geometry/Place Bound Bottom")
		(35 "F.Fab" user "Ref Des/Assembly Top")
		(33 "B.Fab" user "Ref Des/Assembly Bottom")
	)
	(footprint ""
		(layer "F.Cu")
		(at 47.117 -78.867)
		(property "Reference" "C300"
			(at 3.175 0.03937 0)
			(unlocked yes)
			(layer "F.SilkS")
			(effects
				(font
					(size 0.7874 0.5842)
					(thickness 0.1524)
				)
			)
		)
		(property "Value" "VAL*"
			(at 0.0762 3.134106 0)
			(unlocked yes)
			(layer "F.Fab")
			(hide yes)
			(effects
				(font
					(size 0.7874 0.5842)
					(thickness 0.1524)
				)
			)
		)
		(property "Tolerance" "TOL*"
			(at 0.0762 4.048506 0)
			(unlocked yes)
			(layer "Cmts.User")
			(hide yes)
			(effects
				(font
					(size 0.7874 0.5842)
					(thickness 0.1524)
				)
			)
		)
		(property "User Part Number" "PARTNUM*"
			(at 0.1016 5.013706 0)
			(unlocked yes)
			(layer "Cmts.User")
			(hide yes)
			(effects
				(font
					(size 0.7874 0.5842)
					(thickness 0.1524)
				)
			)
		)
		(property "Device Type" "CAPACITOR-G107-0F106-EM,10UF,2A"
			(at 0.0508 2.194306 0)
			(unlocked yes)
			(layer "F.Fab")
			(hide yes)
			(effects
				(font
					(size 0.7874 0.5842)
					(thickness 0.1524)
				)
			)
		)
		(duplicate_pad_numbers_are_jumpers no)
		(fp_line
			(start -1.5748 -0.9398)
			(end -1.5748 0.9398)
			(stroke
				(width 0.1)
				(type default)
			)
			(layer "F.SilkS")
		)
		(fp_line
			(start -1.5748 0.9398)
			(end 1.5748 0.9398)
			(stroke
				(width 0.1)
				(type default)
			)
			(layer "F.SilkS")
		)
		(fp_line
			(start 1.5748 -0.9398)
			(end -1.5748 -0.9398)
			(stroke
				(width 0.1)
				(type default)
			)
			(layer "F.SilkS")
		)
		(fp_line
			(start 1.5748 0.9398)
			(end 1.5748 -0.9398)
			(stroke
				(width 0.1)
				(type default)
			)
			(layer "F.SilkS")
		)
		(fp_rect
			(start -1.5748 0.9398)
			(end 1.5748 -0.9398)
			(stroke
				(width 0)
				(type default)
			)
			(fill no)
			(layer "F.CrtYd")
		)
		(fp_line
			(start -1.016 -0.635)
			(end -1.016 0.635)
			(stroke
				(width 0.1)
				(type default)
			)
			(layer "F.Fab")
		)
		(fp_line
			(start -1.016 0.635)
			(end 1.016 0.635)
			(stroke
				(width 0.1)
				(type default)
			)
			(layer "F.Fab")
		)
		(fp_line
			(start 1.016 -0.635)
			(end -1.016 -0.635)
			(stroke
				(width 0.1)
				(type default)
			)
			(layer "F.Fab")
		)
		(fp_line
			(start 1.016 0.635)
			(end 1.016 -0.635)
			(stroke
				(width 0.1)
				(type default)
			)
			(layer "F.Fab")
		)
		(pad "1" smd rect
			(at -0.8382 0)
			(size 0.9652 1.3716)
			(layers "F.Cu" "F.Mask" "F.Paste")
			(net "UNNAMED_525_CAPACITOR_I16_1")
		)
		(pad "2" smd rect
			(at 0.8382 0)
			(size 0.9652 1.3716)
			(layers "F.Cu" "F.Mask" "F.Paste")
			(net "SG")
		)
		(zone
			(layer "F.Cu")
			(hatch none 0.5)
			(connect_pads
				(clearance 0)
			)
			(min_thickness 0.25)
			(keepout
				(tracks not_allowed)
				(vias allowed)
				(pads allowed)
				(copperpour not_allowed)
				(footprints allowed)
			)
			(placement
				(enabled no)
				(sheetname "")
			)
			(fill
				(thermal_gap 0.5)
				(thermal_bridge_width 0.5)
				(island_removal_mode 0)
			)
			(polygon
				(pts
					(xy 46.8884 -78.232) (xy 47.3456 -78.232) (xy 47.3456 -79.502) (xy 46.8884 -79.502)
				)
			)
		)
		(zone
			(layer "F.Cu")
			(hatch none 0.5)
			(connect_pads
				(clearance 0)
			)
			(min_thickness 0.25)
			(keepout
				(tracks allowed)
				(vias not_allowed)
				(pads allowed)
				(copperpour not_allowed)
				(footprints allowed)
			)
			(placement
				(enabled no)
				(sheetname "")
			)
			(fill
				(thermal_gap 0.5)
				(thermal_bridge_width 0.5)
				(island_removal_mode 0)
			)
			(polygon
				(pts
					(xy 46.8884 -78.232) (xy 47.3456 -78.232) (xy 47.3456 -79.502) (xy 46.8884 -79.502)
				)
			)
		)
	)
	(footprint ""
		(layer "F.Cu")
		(at 153.67 -56.515)
		(property "Reference" "C274"
			(at 1.905 2.19837 0)
			(unlocked yes)
			(layer "F.SilkS")
			(effects
				(font
					(size 0.7874 0.5842)
					(thickness 0.1524)
				)
			)
		)
		(property "Value" "VAL*"
			(at 0.0762 2.067306 0)
			(unlocked yes)
			(layer "F.Fab")
			(hide yes)
			(effects
				(font
					(size 0.7874 0.5842)
					(thickness 0.1524)
				)
			)
		)
		(property "Device Type" "CAPACITOR-G105-0C106-BM,10UF,2A"
			(at 0.0508 1.127506 0)
			(unlocked yes)
			(layer "F.Fab")
			(hide yes)
			(effects
				(font
					(size 0.7874 0.5842)
					(thickness 0.1524)
				)
			)
		)
		(property "User Part Number" "PARTNUM*"
			(at 0.1016 4.023106 0)
			(unlocked yes)
			(layer "Cmts.User")
			(hide yes)
			(effects
				(font
					(size 0.7874 0.5842)
					(thickness 0.1524)
				)
			)
		)
		(property "Tolerance" "TOL*"
			(at 0.0762 3.032506 0)
			(unlocked yes)
			(layer "Cmts.User")
			(hide yes)
			(effects
				(font
					(size 0.7874 0.5842)
					(thickness 0.1524)
				)
			)
		)
		(duplicate_pad_numbers_are_jumpers no)
		(fp_line
			(start -1.143 -0.5588)
			(end -1.143 0.5588)
			(stroke
				(width 0.1)
				(type default)
			)
			(layer "F.SilkS")
		)
		(fp_line
			(start -1.143 0.5588)
			(end 1.143 0.5588)
			(stroke
				(width 0.1)
				(type default)
			)
			(layer "F.SilkS")
		)
		(fp_line
			(start 1.143 -0.5588)
			(end -1.143 -0.5588)
			(stroke
				(width 0.1)
				(type default)
			)
			(layer "F.SilkS")
		)
		(fp_line
			(start 1.143 0.5588)
			(end 1.143 -0.5588)
			(stroke
				(width 0.1)
				(type default)
			)
			(layer "F.SilkS")
		)
		(fp_rect
			(start 1.143 -0.5588)
			(end -1.143 0.5588)
			(stroke
				(width 0)
				(type default)
			)
			(fill no)
			(layer "F.CrtYd")
		)
		(fp_line
			(start -0.508 -0.3048)
			(end -0.508 0.3048)
			(stroke
				(width 0.1)
				(type default)
			)
			(layer "F.Fab")
		)
		(fp_line
			(start -0.508 0.3048)
			(end 0.508 0.3048)
			(stroke
				(width 0.1)
				(type default)
			)
			(layer "F.Fab")
		)
		(fp_line
			(start 0.508 -0.3048)
			(end -0.508 -0.3048)
			(stroke
				(width 0.1)
				(type default)
			)
			(layer "F.Fab")
		)
		(fp_line
			(start 0.508 0.3048)
			(end 0.508 -0.3048)
			(stroke
				(width 0.1)
				(type default)
			)
			(layer "F.Fab")
		)
		(pad "1" smd rect
			(at -0.5334 0)
			(size 0.7112 0.6096)
			(layers "F.Cu" "F.Mask" "F.Paste")
			(net "VDD3V3_SHT31A")
		)
		(pad "2" smd rect
			(at 0.5334 0)
			(size 0.7112 0.6096)
			(layers "F.Cu" "F.Mask" "F.Paste")
			(net "SG")
		)
		(zone
			(layer "F.Cu")
			(hatch none 0.5)
			(connect_pads
				(clearance 0)
			)
			(min_thickness 0.25)
			(keepout
				(tracks allowed)
				(vias not_allowed)
				(pads allowed)
				(copperpour not_allowed)
				(footprints allowed)
			)
			(placement
				(enabled no)
				(sheetname "")
			)
			(fill
				(thermal_gap 0.5)
				(thermal_bridge_width 0.5)
				(island_removal_mode 0)
			)
			(polygon
				(pts
					(xy 153.7462 -56.8198) (xy 153.5938 -56.8198) (xy 153.5938 -56.2102) (xy 153.7462 -56.2102)
				)
			)
		)
	)
	(footprint ""
		(layer "F.Cu")
		(at 100.33 -97.028)
		(property "Reference" "TP14"
			(at -1.0414 -1.36525 0)
			(unlocked yes)
			(layer "F.SilkS")
			(effects
				(font
					(size 0.635 0.4064)
					(thickness 0.1524)
				)
				(justify left)
			)
		)
		(property "Value" ""
			(at 0 0 0)
			(layer "F.Fab")
			(effects
				(font
					(size 1.27 1.27)
				)
			)
		)
		(property "Device Type" "TP_PIONT-TP010CT020B030_PTH-TPA"
			(at -1.341882 0.996696 0)
			(unlocked yes)
			(layer "F.Fab")
			(hide yes)
			(effects
				(font
					(size 0.7874 0.5842)
					(thickness 0.000001)
				)
				(justify left)
			)
		)
		(duplicate_pad_numbers_are_jumpers no)
		(fp_poly
			(pts
				(arc
					(start 0.889 0)
					(mid -0.889 0)
					(end 0.889 0)
				)
			)
			(stroke
				(width 0)
				(type default)
			)
			(fill no)
			(layer "B.CrtYd")
		)
		(fp_poly
			(pts
				(arc
					(start 0.889 0)
					(mid -0.889 0)
					(end 0.889 0)
				)
			)
			(stroke
				(width 0)
				(type default)
			)
			(fill no)
			(layer "F.CrtYd")
		)
		(pad "1" thru_hole circle
			(at 0 0)
			(size 0.508 0.508)
			(drill 0.254)
			(layers "*.Cu" "*.Mask")
			(remove_unused_layers no)
			(net "MUX1_SEL")
			(clearance 0.1016)
			(padstack
				(mode front_inner_back)
				(layer "Inner"
					(shape circle)
					(size 0.508 0.508)
					(clearance 0.1016)
				)
				(layer "B.Cu"
					(shape circle)
					(size 0.762 0.762)
					(clearance -0.0254)
				)
			)
		)
	)
	(footprint ""
		(layer "F.Cu")
		(at 106.807 -22.86 -90)
		(property "Reference" "R235"
			(at -2.667 0.34163 90)
			(unlocked yes)
			(layer "F.SilkS")
			(effects
				(font
					(size 0.7874 0.5842)
					(thickness 0.1524)
				)
			)
		)
		(property "Value" "VAL*"
			(at 0.02032 2.13233 270)
			(unlocked yes)
			(layer "F.Fab")
			(hide yes)
			(effects
				(font
					(size 0.7874 0.5842)
					(thickness 0.1524)
				)
			)
		)
		(property "Device Type" "RESISTOR-G155-14701-01,4.7KOHMA"
			(at 0.008382 1.210564 270)
			(unlocked yes)
			(layer "F.Fab")
			(hide yes)
			(effects
				(font
					(size 0.7874 0.5842)
					(thickness 0.1524)
				)
			)
		)
		(property "User Part Number" "PARTNUM*"
			(at 0.02032 4.024884 270)
			(unlocked yes)
			(layer "Cmts.User")
			(hide yes)
			(effects
				(font
					(size 0.7874 0.5842)
					(thickness 0.1524)
				)
			)
		)
		(property "Tolerance" "TOL*"
			(at 0.044704 3.05435 270)
			(unlocked yes)
			(layer "Cmts.User")
			(hide yes)
			(effects
				(font
					(size 0.7874 0.5842)
					(thickness 0.1524)
				)
			)
		)
		(duplicate_pad_numbers_are_jumpers no)
		(fp_line
			(start -1.143 0.5588)
			(end 1.143 0.5588)
			(stroke
				(width 0.1)
				(type default)
			)
			(layer "F.SilkS")
		)
		(fp_line
			(start 1.143 0.5588)
			(end 1.143 -0.5588)
			(stroke
				(width 0.1)
				(type default)
			)
			(layer "F.SilkS")
		)
		(fp_line
			(start -1.143 -0.5588)
			(end -1.143 0.5588)
			(stroke
				(width 0.1)
				(type default)
			)
			(layer "F.SilkS")
		)
		(fp_line
			(start 1.143 -0.5588)
			(end -1.143 -0.5588)
			(stroke
				(width 0.1)
				(type default)
			)
			(layer "F.SilkS")
		)
		(fp_rect
			(start -1.143 0.5588)
			(end 1.143 -0.5588)
			(stroke
				(width 0)
				(type default)
			)
			(fill no)
			(layer "F.CrtYd")
		)
		(fp_line
			(start -0.508 0.3048)
			(end 0.508 0.3048)
			(stroke
				(width 0.1)
				(type default)
			)
			(layer "F.Fab")
		)
		(fp_line
			(start 0.508 0.3048)
			(end 0.508 -0.3048)
			(stroke
				(width 0.1)
				(type default)
			)
			(layer "F.Fab")
		)
		(fp_line
			(start -0.508 -0.3048)
			(end -0.508 0.3048)
			(stroke
				(width 0.1)
				(type default)
			)
			(layer "F.Fab")
		)
		(fp_line
			(start 0.508 -0.3048)
			(end -0.508 -0.3048)
			(stroke
				(width 0.1)
				(type default)
			)
			(layer "F.Fab")
		)
		(pad "1" smd rect
			(at -0.5334 0 270)
			(size 0.7112 0.6096)
			(layers "F.Cu" "F.Mask" "F.Paste")
			(net "VDD3V3_OSC_200M")
		)
		(pad "2" smd rect
			(at 0.5334 0 270)
			(size 0.7112 0.6096)
			(layers "F.Cu" "F.Mask" "F.Paste")
			(net "CLK_200M_OE")
		)
		(zone
			(layer "F.Cu")
			(hatch none 0.5)
			(connect_pads
				(clearance 0)
			)
			(min_thickness 0.25)
			(keepout
				(tracks allowed)
				(vias not_allowed)
				(pads allowed)
				(copperpour not_allowed)
				(footprints allowed)
			)
			(placement
				(enabled no)
				(sheetname "")
			)
			(fill
				(thermal_gap 0.5)
				(thermal_bridge_width 0.5)
				(island_removal_mode 0)
			)
			(polygon
				(pts
					(xy 106.5022 -22.9362) (xy 106.5022 -22.7838) (xy 107.1118 -22.7838) (xy 107.1118 -22.9362)
				)
			)
		)
	)
	(footprint ""
		(layer "F.Cu")
		(at 137.033 -57.3024 -90)
		(property "Reference" "L9"
			(at 0.0762 2.75463 90)
			(unlocked yes)
			(layer "F.SilkS")
			(effects
				(font
					(size 0.7874 0.5842)
					(thickness 0.1524)
				)
				(justify left)
			)
		)
		(property "Value" "VAL*"
			(at -0.9398 3.70967 270)
			(unlocked yes)
			(layer "F.Fab")
			(hide yes)
			(effects
				(font
					(size 0.7874 0.5842)
					(thickness 0.1524)
				)
				(justify left)
			)
		)
		(property "Tolerance" "TOL*"
			(at -0.9906 5.00507 270)
			(unlocked yes)
			(layer "Cmts.User")
			(hide yes)
			(effects
				(font
					(size 0.7874 0.5842)
					(thickness 0.1524)
				)
				(justify left)
			)
		)
		(property "User Part Number" "PARTNUM*"
			(at -2.54 2.46507 270)
			(unlocked yes)
			(layer "Cmts.User")
			(hide yes)
			(effects
				(font
					(size 0.7874 0.5842)
					(thickness 0.1524)
				)
				(justify left)
			)
		)
		(property "Device Type" "FERRITEBEAD-G191-10101-01,26OHA"
			(at -0.9906 1.22047 270)
			(unlocked yes)
			(layer "F.Fab")
			(hide yes)
			(effects
				(font
					(size 0.7874 0.5842)
					(thickness 0.1524)
				)
				(justify left)
			)
		)
		(duplicate_pad_numbers_are_jumpers no)
		(fp_line
			(start -1.3208 0.7112)
			(end -1.3208 -0.7112)
			(stroke
				(width 0.1)
				(type default)
			)
			(layer "F.SilkS")
		)
		(fp_line
			(start 1.3208 0.7112)
			(end -1.3208 0.7112)
			(stroke
				(width 0.1)
				(type default)
			)
			(layer "F.SilkS")
		)
		(fp_line
			(start -1.3208 -0.7112)
			(end 1.3208 -0.7112)
			(stroke
				(width 0.1)
				(type default)
			)
			(layer "F.SilkS")
		)
		(fp_line
			(start 1.3208 -0.7112)
			(end 1.3208 0.7112)
			(stroke
				(width 0.1)
				(type default)
			)
			(layer "F.SilkS")
		)
		(fp_rect
			(start -1.3208 0.7112)
			(end 1.3208 -0.7112)
			(stroke
				(width 0)
				(type default)
			)
			(fill no)
			(layer "F.CrtYd")
		)
		(fp_line
			(start -0.8128 0.4572)
			(end -0.8128 -0.4572)
			(stroke
				(width 0.1)
				(type default)
			)
			(layer "F.Fab")
		)
		(fp_line
			(start 0.8128 0.4572)
			(end -0.8128 0.4572)
			(stroke
				(width 0.1)
				(type default)
			)
			(layer "F.Fab")
		)
		(fp_line
			(start -0.8128 -0.4572)
			(end 0.8128 -0.4572)
			(stroke
				(width 0.1)
				(type default)
			)
			(layer "F.Fab")
		)
		(fp_line
			(start 0.8128 -0.4572)
			(end 0.8128 0.4572)
			(stroke
				(width 0.1)
				(type default)
			)
			(layer "F.Fab")
		)
		(pad "1" smd rect
			(at -0.6858 0 270)
			(size 0.762 0.8636)
			(layers "F.Cu" "F.Mask" "F.Paste")
			(net "XP12R0V")
		)
		(pad "2" smd rect
			(at 0.6858 0 270)
			(size 0.762 0.8636)
			(layers "F.Cu" "F.Mask" "F.Paste")
			(net "VIN_XP1R0V")
		)
		(zone
			(layer "F.Cu")
			(hatch none 0.5)
			(connect_pads
				(clearance 0)
			)
			(min_thickness 0.25)
			(keepout
				(tracks allowed)
				(vias not_allowed)
				(pads allowed)
				(copperpour not_allowed)
				(footprints allowed)
			)
			(placement
				(enabled no)
				(sheetname "")
			)
			(fill
				(thermal_gap 0.5)
				(thermal_bridge_width 0.5)
				(island_removal_mode 0)
			)
			(polygon
				(pts
					(xy 136.5758 -57.4548) (xy 136.5758 -57.15) (xy 137.4902 -57.15) (xy 137.4902 -57.4548)
				)
			)
		)
		(zone
			(layer "F.Cu")
			(hatch none 0.5)
			(connect_pads
				(clearance 0)
			)
			(min_thickness 0.25)
			(keepout
				(tracks not_allowed)
				(vias allowed)
				(pads allowed)
				(copperpour not_allowed)
				(footprints allowed)
			)
			(placement
				(enabled no)
				(sheetname "")
			)
			(fill
				(thermal_gap 0.5)
				(thermal_bridge_width 0.5)
				(island_removal_mode 0)
			)
			(polygon
				(pts
					(xy 136.5758 -57.4548) (xy 136.5758 -57.15) (xy 137.4902 -57.15) (xy 137.4902 -57.4548)
				)
			)
		)
	)
)
